# BASEBOARD_FAB2 (Tioga Pass) — schematic netlist excerpt (pin names and nets, part order shuffled) for the footprints in the layout excerpt that follows; sources: Cadence DE-HDL packaged netlist, KiCad conversion of Wiwynn_Tioga_Pass_MB.brd

J6U1  SCONN288_H44441003  SCONN  pkg PIP  page 46
  \12v\(1)  = P12V_NVDIMM_ABC
  VSS(93)  = GND
  DQ(4)  = M_B_DQ<4>
  VSS(92)  = GND
  DQ(0)  = M_B_DQ<0>
  VSS(91)  = GND
  DQS9P  = M_B_DQS_DP<9>
  DQS9N  = M_B_DQS_DN<9>
  VSS(90)  = GND
  DQ(6)  = M_B_DQ<6>
  VSS(89)  = GND
  DQ(2)  = M_B_DQ<2>
  VSS(88)  = GND
  DQ(12)  = M_B_DQ<12>
  VSS(87)  = GND
  DQ(8)  = M_B_DQ<8>
  VSS(86)  = GND
  DQS10P  = M_B_DQS_DP<10>
  DQS10N  = M_B_DQS_DN<10>
  VSS(85)  = GND
  DQ(14)  = M_B_DQ<14>
  VSS(84)  = GND
  DQ(10)  = M_B_DQ<10>
  VSS(83)  = GND
  DQ(20)  = M_B_DQ<20>
  VSS(82)  = GND
  DQ(16)  = M_B_DQ<16>
  VSS(81)  = GND
  DQS11P  = M_B_DQS_DP<11>
  DQS11N  = M_B_DQS_DN<11>
  VSS(80)  = GND
  DQ(22)  = M_B_DQ<22>
  VSS(79)  = GND
  DQ(18)  = M_B_DQ<18>
  VSS(78)  = GND
  DQ(28)  = M_B_DQ<28>
  VSS(77)  = GND
  DQ(24)  = M_B_DQ<24>
  VSS(76)  = GND
  DQS12P  = M_B_DQS_DP<12>
  DQS12N  = M_B_DQS_DN<12>
  VSS(75)  = GND
  DQ(30)  = M_B_DQ<30>
  VSS(74)  = GND
  DQ(26)  = M_B_DQ<26>
  VSS(73)  = GND
  CB(4)  = M_B_ECC<4>
  VSS(72)  = GND
  CB(0)  = M_B_ECC<0>
  VSS(71)  = GND
  DQS17P  = M_B_DQS_DP<17>
  DQS17N  = M_B_DQS_DN<17>
  VSS(70)  = GND
  CB(6)  = M_B_ECC<6>
  VSS(69)  = GND
  CB(2)  = M_B_ECC<2>
  VSS(68)  = GND
  RESET_N  = M_ABC_RST_N
  VDD(25)  = PVDDQ_ABC
  CKE(0)  = M_B_CKE<2>
  VDD(24)  = PVDDQ_ABC
  ACT_N  = M_B_ACT_N
  BG(0)  = M_B_BG<0>
  VDD(23)  = PVDDQ_ABC
  A12  = M_B_MA<12>
  A9  = M_B_MA<9>
  VDD(22)  = PVDDQ_ABC
  A8  = M_B_MA<8>
  A6  = M_B_MA<6>
  VDD(21)  = PVDDQ_ABC
  A3  = M_B_MA<3>
  A1  = M_B_MA<1>
  VDD(20)  = PVDDQ_ABC
  CK0P  = M_B_CLK_DP<2>
  CK0N  = M_B_CLK_DN<2>
  VDD(19)  = PVDDQ_ABC
  VTT(1)  = PVTT_ABC
  EVENT_N  = FM_DIMM_EVENT_COD_N
  A0  = M_B_MA<0>
  VDD(18)  = PVDDQ_ABC
  BA(0)  = M_B_BA<0>
  A16_RAS_N  = M_B_MA<16>
  VDD(17)  = PVDDQ_ABC
  S0_N  = M_B_CS_N<4>
  VDD(16)  = PVDDQ_ABC
  A15_CAS_N  = M_B_MA<15>
  ODT(0)  = M_B_ODT<2>
  VDD(15)  = PVDDQ_ABC
  S1_N  = M_B_CS_N<5>
  VDD(14)  = PVDDQ_ABC
  ODT(1)  = M_B_ODT<3>
  VDD(13)  = PVDDQ_ABC
  S2_N_C(0)  = M_B_CS_N<6>
  VSS(67)  = GND
  DQ(36)  = M_B_DQ<36>
  VSS(66)  = GND
  DQ(32)  = M_B_DQ<32>
  VSS(65)  = GND
  DQS13P  = M_B_DQS_DP<13>
  DQS13N  = M_B_DQS_DN<13>
  VSS(64)  = GND
  DQ(38)  = M_B_DQ<38>
  VSS(63)  = GND
  DQ(34)  = M_B_DQ<34>
  VSS(62)  = GND
  DQ(44)  = M_B_DQ<44>
  VSS(61)  = GND
  DQ(40)  = M_B_DQ<40>
  VSS(60)  = GND
  DQS14P  = M_B_DQS_DP<14>
  DQS14N  = M_B_DQS_DN<14>
  VSS(59)  = GND
  DQ(46)  = M_B_DQ<46>
  VSS(58)  = GND
  DQ(42)  = M_B_DQ<42>
  VSS(57)  = GND
  DQ(52)  = M_B_DQ<52>
  VSS(56)  = GND
  DQ(48)  = M_B_DQ<48>
  VSS(55)  = GND
  DQS15P  = M_B_DQS_DP<15>
  DQS15N  = M_B_DQS_DN<15>
  VSS(54)  = GND
  DQ(54)  = M_B_DQ<54>
  VSS(53)  = GND
  DQ(50)  = M_B_DQ<50>
  VSS(52)  = GND
  DQ(60)  = M_B_DQ<60>
  VSS(51)  = GND
  DQ(56)  = M_B_DQ<56>
  VSS(50)  = GND
  DQS16P  = M_B_DQS_DP<16>
  DQS16N  = M_B_DQS_DN<16>
  VSS(49)  = GND
  DQ(62)  = M_B_DQ<62>
  VSS(48)  = GND
  DQ(58)  = M_B_DQ<58>
  VSS(47)  = GND
  SA(0)  = PVPP_ABC
  SA(1)  = PVPP_ABC
  SCL  = SMB_DDR_ABC_VPP_SCL
  VPP(4)  = PVPP_ABC
  VPP(3)  = PVPP_ABC
  RFU(2)  = TP_CH_B_DIMM_B1_RFU_2
  \12v\(0)  = P12V_NVDIMM_ABC
  VREFCA  = M_B_VREF
  VSS(46)  = GND
  DQ(5)  = M_B_DQ<5>
  VSS(45)  = GND
  DQ(1)  = M_B_DQ<1>
  VSS(44)  = GND
  DQS0N  = M_B_DQS_DN<0>
  DQS0P  = M_B_DQS_DP<0>
  VSS(43)  = GND
  DQ(7)  = M_B_DQ<7>
  VSS(42)  = GND
  DQ(3)  = M_B_DQ<3>
  VSS(41)  = GND
  DQ(13)  = M_B_DQ<13>
  VSS(40)  = GND
  DQ(9)  = M_B_DQ<9>
  VSS(39)  = GND
  DQS1N  = M_B_DQS_DN<1>
  DQS1P  = M_B_DQS_DP<1>
  VSS(38)  = GND
  DQ(15)  = M_B_DQ<15>
  VSS(37)  = GND
  DQ(11)  = M_B_DQ<11>
  VSS(36)  = GND
  DQ(21)  = M_B_DQ<21>
  VSS(35)  = GND
  DQ(17)  = M_B_DQ<17>
  VSS(34)  = GND
  DQS2N  = M_B_DQS_DN<2>
  DQS2P  = M_B_DQS_DP<2>
  VSS(33)  = GND
  DQ(23)  = M_B_DQ<23>
  VSS(32)  = GND
  DQ(19)  = M_B_DQ<19>
  VSS(31)  = GND
  DQ(29)  = M_B_DQ<29>
  VSS(30)  = GND
  DQ(25)  = M_B_DQ<25>
  VSS(29)  = GND
  DQS3N  = M_B_DQS_DN<3>
  DQS3P  = M_B_DQS_DP<3>
  VSS(28)  = GND
  DQ(31)  = M_B_DQ<31>
  VSS(27)  = GND
  DQ(27)  = M_B_DQ<27>
  VSS(26)  = GND
  CB(5)  = M_B_ECC<5>
  VSS(25)  = GND
  CB(1)  = M_B_ECC<1>
  VSS(24)  = GND
  DQS8N  = M_B_DQS_DN<8>
  DQS8P  = M_B_DQS_DP<8>
  VSS(23)  = GND
  CB(7)  = M_B_ECC<7>
  VSS(22)  = GND
  CB(3)  = M_B_ECC<3>
  VSS(21)  = GND
  CKE(1)  = M_B_CKE<3>
  VDD(12)  = PVDDQ_ABC
  RFU(0)  = TP_CH_B_DIMM_B1_RFU_0
  VDD(11)  = PVDDQ_ABC
  BG(1)  = M_B_BG<1>
  ALERT_N  = M_B_ALERT_N
  VDD(10)  = PVDDQ_ABC
  A11  = M_B_MA<11>
  A7  = M_B_MA<7>
  VDD(9)  = PVDDQ_ABC
  A5  = M_B_MA<5>
  A4  = M_B_MA<4>
  VDD(8)  = PVDDQ_ABC
  A2  = M_B_MA<2>
  VDD(7)  = PVDDQ_ABC
  CK1P  = M_B_CLK_DP<3>
  CK1N  = M_B_CLK_DN<3>
  VDD(6)  = PVDDQ_ABC
  VTT(0)  = PVTT_ABC
  PAR  = M_B_PAR
  VDD(5)  = PVDDQ_ABC
  BA(1)  = M_B_BA<1>
  A10  = M_B_MA<10>
  VDD(4)  = PVDDQ_ABC
  RFU(1)  = TP_CH_B_DIMM_B1_RFU_1
  A14_WE_N  = M_B_MA<14>
  VDD(3)  = PVDDQ_ABC
  SAVE_N_NC  = FM_ADR_COMPLETE_ABC_N
  VDD(2)  = PVDDQ_ABC
  A13  = M_B_MA<13>
  VDD(1)  = PVDDQ_ABC
  A17  = M_B_MA<17>
  C(2)  = M_B_C<2>
  VDD(0)  = PVDDQ_ABC
  S3_N_C(1)  = M_B_CS_N<7>
  SA(2)  = GND
  VSS(20)  = GND
  DQ(37)  = M_B_DQ<37>
  VSS(19)  = GND
  DQ(33)  = M_B_DQ<33>
  VSS(18)  = GND
  DQS4N  = M_B_DQS_DN<4>
  DQS4P  = M_B_DQS_DP<4>
  VSS(17)  = GND
  DQ(39)  = M_B_DQ<39>
  VSS(16)  = GND
  DQ(35)  = M_B_DQ<35>
  VSS(15)  = GND
  DQ(45)  = M_B_DQ<45>
  VSS(14)  = GND
  DQ(41)  = M_B_DQ<41>
  VSS(13)  = GND
  DQS5N  = M_B_DQS_DN<5>
  DQS5P  = M_B_DQS_DP<5>
  VSS(12)  = GND
  DQ(47)  = M_B_DQ<47>
  VSS(11)  = GND
  DQ(43)  = M_B_DQ<43>
  VSS(10)  = GND
  DQ(53)  = M_B_DQ<53>
  VSS(9)  = GND
  DQ(49)  = M_B_DQ<49>
  VSS(8)  = GND
  DQS6N  = M_B_DQS_DN<6>
  DQS6P  = M_B_DQS_DP<6>
  VSS(7)  = GND
  DQ(55)  = M_B_DQ<55>
  VSS(6)  = GND
  DQ(51)  = M_B_DQ<51>
  VSS(5)  = GND
  DQ(61)  = M_B_DQ<61>
  VSS(4)  = GND
  DQ(57)  = M_B_DQ<57>
  VSS(3)  = GND
  DQS7N  = M_B_DQS_DN<7>
  DQS7P  = M_B_DQS_DP<7>
  VSS(2)  = GND
  DQ(63)  = M_B_DQ<63>
  VSS(1)  = GND
  DQ(59)  = M_B_DQ<59>
  VSS(0)  = GND
  VDDSPD  = PVPP_ABC
  SDA  = SMB_DDR_ABC_VPP_SDA
  VPP(1)  = PVPP_ABC
  VPP(0)  = PVPP_ABC
  VPP(2)  = PVPP_ABC

(kicad_pcb
	(version 20260206)
	(generator "pcbnew")
	(generator_version "10.0")
	(general
		(thickness 1.6)
		(legacy_teardrops no)
	)
	(paper "A4")
	(title_block
		(title "Wiwynn_Tioga_Pass_MB.brd")
		(comment 1 "Tioga Pass / footprint 2988 of 4770 (J6U1), pads 152-201 of 291")
	)
	(layers
		(0 "F.Cu" signal "TOP")
		(4 "In1.Cu" signal "L2GND")
		(6 "In2.Cu" signal "L3")
		(8 "In3.Cu" signal "L4GND")
		(10 "In4.Cu" signal "L5")
		(12 "In5.Cu" signal "L6GND")
		(14 "In6.Cu" signal "L7VCC")
		(16 "In7.Cu" signal "L8VCC")
		(18 "In8.Cu" signal "L9GND")
		(20 "In9.Cu" signal "L10")
		(22 "In10.Cu" signal "L11GND")
		(24 "In11.Cu" signal "L12")
		(26 "In12.Cu" signal "L13GND")
		(2 "B.Cu" signal "BOTTOM")
		(9 "F.Adhes" user "F.Adhesive")
		(11 "B.Adhes" user "B.Adhesive")
		(13 "F.Paste" user "Package Geometry/Pastemask Top")
		(15 "B.Paste" user "Package Geometry/Pastemask Bottom")
		(5 "F.SilkS" user "Ref Des/Silkscreen Top")
		(7 "B.SilkS" user "Ref Des/Silkscreen Bottom")
		(1 "F.Mask" user "Board Geometry/Soldermask Top")
		(3 "B.Mask" user "Board Geometry/Soldermask Bottom")
		(17 "Dwgs.User" user "User.Drawings")
		(19 "Cmts.User" user "User.Comments")
		(21 "Eco1.User" user "User.Eco1")
		(23 "Eco2.User" user "User.Eco2")
		(25 "Edge.Cuts" user "Board Geometry/Outline")
		(27 "Margin" user)
		(31 "F.CrtYd" user "Package Geometry/Place Bound Top")
		(29 "B.CrtYd" user "Package Geometry/Place Bound Bottom")
		(35 "F.Fab" user "Ref Des/Assembly Top")
		(33 "B.Fab" user "Ref Des/Assembly Bottom")
	)
	(footprint ""
		(layer "B.Cu")
		(at 194.700398 -15.222982 90)
		(property "Reference" "J6U1"
			(at 2.530348 39.10711 0)
			(unlocked yes)
			(layer "B.SilkS")
			(effects
				(font
					(size 0.7874 0.5842)
					(thickness 0.1524)
				)
				(justify left mirror)
			)
		)
		(property "Value" ""
			(at 0 0 90)
			(layer "B.Fab")
			(effects
				(font
					(size 1.27 1.27)
				)
				(justify mirror)
			)
		)
		(duplicate_pad_numbers_are_jumpers no)
		(pad "149" smd rect
			(at -4.59994 3.400044 270)
			(size 1.8034 0.508)
			(layers "B.Cu" "B.Mask" "B.Paste")
			(net "GND")
		)
		(pad "150" smd rect
			(at -4.59994 4.249928 270)
			(size 1.8034 0.508)
			(layers "B.Cu" "B.Mask" "B.Paste")
			(net "M_B_DQ<1>")
		)
		(pad "151" smd rect
			(at -4.59994 5.100066 270)
			(size 1.8034 0.508)
			(layers "B.Cu" "B.Mask" "B.Paste")
			(net "GND")
		)
		(pad "152" smd rect
			(at -4.59994 5.94995 270)
			(size 1.8034 0.508)
			(layers "B.Cu" "B.Mask" "B.Paste")
			(net "M_B_DQS_DN<0>")
		)
		(pad "153" smd rect
			(at -4.59994 6.800088 270)
			(size 1.8034 0.508)
			(layers "B.Cu" "B.Mask" "B.Paste")
			(net "M_B_DQS_DP<0>")
		)
		(pad "154" smd rect
			(at -4.59994 7.649972 270)
			(size 1.8034 0.508)
			(layers "B.Cu" "B.Mask" "B.Paste")
			(net "GND")
		)
		(pad "155" smd rect
			(at -4.59994 8.50011 270)
			(size 1.8034 0.508)
			(layers "B.Cu" "B.Mask" "B.Paste")
			(net "M_B_DQ<7>")
		)
		(pad "156" smd rect
			(at -4.59994 9.349994 270)
			(size 1.8034 0.508)
			(layers "B.Cu" "B.Mask" "B.Paste")
			(net "GND")
		)
		(pad "157" smd rect
			(at -4.59994 10.199878 270)
			(size 1.8034 0.508)
			(layers "B.Cu" "B.Mask" "B.Paste")
			(net "M_B_DQ<3>")
		)
		(pad "158" smd rect
			(at -4.59994 11.050016 270)
			(size 1.8034 0.508)
			(layers "B.Cu" "B.Mask" "B.Paste")
			(net "GND")
		)
		(pad "159" smd rect
			(at -4.59994 11.8999 270)
			(size 1.8034 0.508)
			(layers "B.Cu" "B.Mask" "B.Paste")
			(net "M_B_DQ<13>")
		)
		(pad "160" smd rect
			(at -4.59994 12.750038 270)
			(size 1.8034 0.508)
			(layers "B.Cu" "B.Mask" "B.Paste")
			(net "GND")
		)
		(pad "161" smd rect
			(at -4.59994 13.599922 270)
			(size 1.8034 0.508)
			(layers "B.Cu" "B.Mask" "B.Paste")
			(net "M_B_DQ<9>")
		)
		(pad "162" smd rect
			(at -4.59994 14.45006 270)
			(size 1.8034 0.508)
			(layers "B.Cu" "B.Mask" "B.Paste")
			(net "GND")
		)
		(pad "163" smd rect
			(at -4.59994 15.299944 270)
			(size 1.8034 0.508)
			(layers "B.Cu" "B.Mask" "B.Paste")
			(net "M_B_DQS_DN<1>")
		)
		(pad "164" smd rect
			(at -4.59994 16.150082 270)
			(size 1.8034 0.508)
			(layers "B.Cu" "B.Mask" "B.Paste")
			(net "M_B_DQS_DP<1>")
		)
		(pad "165" smd rect
			(at -4.59994 16.999966 270)
			(size 1.8034 0.508)
			(layers "B.Cu" "B.Mask" "B.Paste")
			(net "GND")
		)
		(pad "166" smd rect
			(at -4.59994 17.850104 270)
			(size 1.8034 0.508)
			(layers "B.Cu" "B.Mask" "B.Paste")
			(net "M_B_DQ<15>")
		)
		(pad "167" smd rect
			(at -4.59994 18.699988 270)
			(size 1.8034 0.508)
			(layers "B.Cu" "B.Mask" "B.Paste")
			(net "GND")
		)
		(pad "168" smd rect
			(at -4.59994 19.550126 270)
			(size 1.8034 0.508)
			(layers "B.Cu" "B.Mask" "B.Paste")
			(net "M_B_DQ<11>")
		)
		(pad "169" smd rect
			(at -4.59994 20.40001 270)
			(size 1.8034 0.508)
			(layers "B.Cu" "B.Mask" "B.Paste")
			(net "GND")
		)
		(pad "170" smd rect
			(at -4.59994 21.249894 270)
			(size 1.8034 0.508)
			(layers "B.Cu" "B.Mask" "B.Paste")
			(net "M_B_DQ<21>")
		)
		(pad "171" smd rect
			(at -4.59994 22.100032 270)
			(size 1.8034 0.508)
			(layers "B.Cu" "B.Mask" "B.Paste")
			(net "GND")
		)
		(pad "172" smd rect
			(at -4.59994 22.949916 270)
			(size 1.8034 0.508)
			(layers "B.Cu" "B.Mask" "B.Paste")
			(net "M_B_DQ<17>")
		)
		(pad "173" smd rect
			(at -4.59994 23.800054 270)
			(size 1.8034 0.508)
			(layers "B.Cu" "B.Mask" "B.Paste")
			(net "GND")
		)
		(pad "174" smd rect
			(at -4.59994 24.649938 270)
			(size 1.8034 0.508)
			(layers "B.Cu" "B.Mask" "B.Paste")
			(net "M_B_DQS_DN<2>")
		)
		(pad "175" smd rect
			(at -4.59994 25.500076 270)
			(size 1.8034 0.508)
			(layers "B.Cu" "B.Mask" "B.Paste")
			(net "M_B_DQS_DP<2>")
		)
		(pad "176" smd rect
			(at -4.59994 26.34996 270)
			(size 1.8034 0.508)
			(layers "B.Cu" "B.Mask" "B.Paste")
			(net "GND")
		)
		(pad "177" smd rect
			(at -4.59994 27.200098 270)
			(size 1.8034 0.508)
			(layers "B.Cu" "B.Mask" "B.Paste")
			(net "M_B_DQ<23>")
		)
		(pad "178" smd rect
			(at -4.59994 28.049982 270)
			(size 1.8034 0.508)
			(layers "B.Cu" "B.Mask" "B.Paste")
			(net "GND")
		)
		(pad "179" smd rect
			(at -4.59994 28.90012 270)
			(size 1.8034 0.508)
			(layers "B.Cu" "B.Mask" "B.Paste")
			(net "M_B_DQ<19>")
		)
		(pad "180" smd rect
			(at -4.59994 29.750004 270)
			(size 1.8034 0.508)
			(layers "B.Cu" "B.Mask" "B.Paste")
			(net "GND")
		)
		(pad "181" smd rect
			(at -4.59994 30.599888 270)
			(size 1.8034 0.508)
			(layers "B.Cu" "B.Mask" "B.Paste")
			(net "M_B_DQ<29>")
		)
		(pad "182" smd rect
			(at -4.59994 31.450026 270)
			(size 1.8034 0.508)
			(layers "B.Cu" "B.Mask" "B.Paste")
			(net "GND")
		)
		(pad "183" smd rect
			(at -4.59994 32.29991 270)
			(size 1.8034 0.508)
			(layers "B.Cu" "B.Mask" "B.Paste")
			(net "M_B_DQ<25>")
		)
		(pad "184" smd rect
			(at -4.59994 33.150048 270)
			(size 1.8034 0.508)
			(layers "B.Cu" "B.Mask" "B.Paste")
			(net "GND")
		)
		(pad "185" smd rect
			(at -4.59994 33.999932 270)
			(size 1.8034 0.508)
			(layers "B.Cu" "B.Mask" "B.Paste")
			(net "M_B_DQS_DN<3>")
		)
		(pad "186" smd rect
			(at -4.59994 34.85007 270)
			(size 1.8034 0.508)
			(layers "B.Cu" "B.Mask" "B.Paste")
			(net "M_B_DQS_DP<3>")
		)
		(pad "187" smd rect
			(at -4.59994 35.699954 270)
			(size 1.8034 0.508)
			(layers "B.Cu" "B.Mask" "B.Paste")
			(net "GND")
		)
		(pad "188" smd rect
			(at -4.59994 36.550092 270)
			(size 1.8034 0.508)
			(layers "B.Cu" "B.Mask" "B.Paste")
			(net "M_B_DQ<31>")
		)
		(pad "189" smd rect
			(at -4.59994 37.399976 270)
			(size 1.8034 0.508)
			(layers "B.Cu" "B.Mask" "B.Paste")
			(net "GND")
		)
		(pad "190" smd rect
			(at -4.59994 38.250114 270)
			(size 1.8034 0.508)
			(layers "B.Cu" "B.Mask" "B.Paste")
			(net "M_B_DQ<27>")
		)
		(pad "191" smd rect
			(at -4.59994 39.099998 270)
			(size 1.8034 0.508)
			(layers "B.Cu" "B.Mask" "B.Paste")
			(net "GND")
		)
		(pad "192" smd rect
			(at -4.59994 39.949882 270)
			(size 1.8034 0.508)
			(layers "B.Cu" "B.Mask" "B.Paste")
			(net "M_B_ECC<5>")
		)
		(pad "193" smd rect
			(at -4.59994 40.80002 270)
			(size 1.8034 0.508)
			(layers "B.Cu" "B.Mask" "B.Paste")
			(net "GND")
		)
		(pad "194" smd rect
			(at -4.59994 41.649904 270)
			(size 1.8034 0.508)
			(layers "B.Cu" "B.Mask" "B.Paste")
			(net "M_B_ECC<1>")
		)
		(pad "195" smd rect
			(at -4.59994 42.500042 270)
			(size 1.8034 0.508)
			(layers "B.Cu" "B.Mask" "B.Paste")
			(net "GND")
		)
		(pad "196" smd rect
			(at -4.59994 43.349926 270)
			(size 1.8034 0.508)
			(layers "B.Cu" "B.Mask" "B.Paste")
			(net "M_B_DQS_DN<8>")
		)
		(pad "197" smd rect
			(at -4.59994 44.200064 270)
			(size 1.8034 0.508)
			(layers "B.Cu" "B.Mask" "B.Paste")
			(net "M_B_DQS_DP<8>")
		)
		(pad "198" smd rect
			(at -4.59994 45.049948 270)
			(size 1.8034 0.508)
			(layers "B.Cu" "B.Mask" "B.Paste")
			(net "GND")
		)
	)
)
